# BASEBOARD_FAB2 (Tioga Pass) — schematic netlist excerpt (pin names and nets, part order shuffled) for the footprints in the layout excerpt that follows; sources: Cadence DE-HDL packaged netlist, KiCad conversion of Wiwynn_Tioga_Pass_MB.brd

C4A10  CAP  1.0UF 16V 10% X6S  pkg 0402  page 222 : A = VR_PVTT_DEF_BIAS ; B = GND
L4C3  IND-120NH-30-GP  pkg DISCRET-GB2  page 204 : S = VR_PVCCIN_CPU0_PHASE5 ; F = PVCCIN_CPU0
R4B1  RES  0.0 5% CHIP  pkg 0402  page 234 : A = FM_PVPP_CPU1_EN ; B = FM_PVPP_PVDDQ_CPU1_EN_KLM

(kicad_pcb
	(version 20260206)
	(generator "pcbnew")
	(generator_version "10.0")
	(general
		(thickness 1.6)
		(legacy_teardrops no)
	)
	(paper "A4")
	(title_block
		(title "Wiwynn_Tioga_Pass_MB.brd")
		(comment 1 "Tioga Pass / footprints 492-494 of 4770")
	)
	(layers
		(0 "F.Cu" signal "TOP")
		(4 "In1.Cu" signal "L2GND")
		(6 "In2.Cu" signal "L3")
		(8 "In3.Cu" signal "L4GND")
		(10 "In4.Cu" signal "L5")
		(12 "In5.Cu" signal "L6GND")
		(14 "In6.Cu" signal "L7VCC")
		(16 "In7.Cu" signal "L8VCC")
		(18 "In8.Cu" signal "L9GND")
		(20 "In9.Cu" signal "L10")
		(22 "In10.Cu" signal "L11GND")
		(24 "In11.Cu" signal "L12")
		(26 "In12.Cu" signal "L13GND")
		(2 "B.Cu" signal "BOTTOM")
		(9 "F.Adhes" user "F.Adhesive")
		(11 "B.Adhes" user "B.Adhesive")
		(13 "F.Paste" user "Package Geometry/Pastemask Top")
		(15 "B.Paste" user "Package Geometry/Pastemask Bottom")
		(5 "F.SilkS" user "Ref Des/Silkscreen Top")
		(7 "B.SilkS" user "Ref Des/Silkscreen Bottom")
		(1 "F.Mask" user "Board Geometry/Soldermask Top")
		(3 "B.Mask" user "Board Geometry/Soldermask Bottom")
		(17 "Dwgs.User" user "User.Drawings")
		(19 "Cmts.User" user "User.Comments")
		(21 "Eco1.User" user "User.Eco1")
		(23 "Eco2.User" user "User.Eco2")
		(25 "Edge.Cuts" user "Board Geometry/Outline")
		(27 "Margin" user)
		(31 "F.CrtYd" user "Package Geometry/Place Bound Top")
		(29 "B.CrtYd" user "Package Geometry/Place Bound Bottom")
		(35 "F.Fab" user "Ref Des/Assembly Top")
		(33 "B.Fab" user "Ref Des/Assembly Bottom")
	)
	(footprint ""
		(layer "F.Cu")
		(at 172.3771 -132.4864 90)
		(property "Reference" "R4B1"
			(at 0 0 90)
			(layer "F.SilkS")
			(hide yes)
			(effects
				(font
					(size 1.27 1.27)
				)
			)
		)
		(property "Value" ""
			(at 0 0 90)
			(layer "F.Fab")
			(effects
				(font
					(size 1.27 1.27)
				)
			)
		)
		(duplicate_pad_numbers_are_jumpers no)
		(fp_poly
			(pts
				(xy -0.2794 -0.1016) (xy 0.2794 -0.1016) (xy 0.2794 0.9906) (xy -0.2794 0.9906)
			)
			(stroke
				(width 0)
				(type default)
			)
			(fill no)
			(layer "F.CrtYd")
		)
		(fp_line
			(start 0.2794 -0.1016)
			(end -0.2794 -0.1016)
			(stroke
				(width 0.1)
				(type default)
			)
			(layer "F.Fab")
		)
		(fp_line
			(start -0.2794 -0.1016)
			(end -0.2794 0.9906)
			(stroke
				(width 0.1)
				(type default)
			)
			(layer "F.Fab")
		)
		(fp_line
			(start 0.2794 0.9906)
			(end 0.2794 -0.1016)
			(stroke
				(width 0.1)
				(type default)
			)
			(layer "F.Fab")
		)
		(fp_line
			(start -0.2794 0.9906)
			(end 0.2794 0.9906)
			(stroke
				(width 0.1)
				(type default)
			)
			(layer "F.Fab")
		)
		(pad "1" smd rect
			(at 0 0 90)
			(size 0.508 0.508)
			(layers "F.Cu" "F.Mask" "F.Paste")
			(net "FM_PVPP_CPU1_EN")
		)
		(pad "2" smd rect
			(at 0 0.889 90)
			(size 0.508 0.508)
			(layers "F.Cu" "F.Mask" "F.Paste")
			(net "FM_PVPP_PVDDQ_CPU1_EN_KLM")
		)
		(zone
			(layer "F.Cu")
			(hatch none 0.5)
			(connect_pads
				(clearance 0)
			)
			(min_thickness 0.25)
			(keepout
				(tracks allowed)
				(vias not_allowed)
				(pads allowed)
				(copperpour not_allowed)
				(footprints allowed)
			)
			(placement
				(enabled no)
				(sheetname "")
			)
			(fill
				(thermal_gap 0.5)
				(thermal_bridge_width 0.5)
				(island_removal_mode 0)
			)
			(polygon
				(pts
					(xy 172.6311 -132.2324) (xy 172.6311 -132.7404) (xy 173.0121 -132.7404) (xy 173.0121 -132.2324)
				)
			)
		)
		(zone
			(layer "F.Cu")
			(hatch none 0.5)
			(connect_pads
				(clearance 0)
			)
			(min_thickness 0.25)
			(keepout
				(tracks not_allowed)
				(vias allowed)
				(pads allowed)
				(copperpour not_allowed)
				(footprints allowed)
			)
			(placement
				(enabled no)
				(sheetname "")
			)
			(fill
				(thermal_gap 0.5)
				(thermal_bridge_width 0.5)
				(island_removal_mode 0)
			)
			(polygon
				(pts
					(xy 173.0121 -132.2324) (xy 173.0121 -132.7404) (xy 172.6311 -132.7404) (xy 172.6311 -132.2324)
				)
			)
		)
	)
	(footprint ""
		(layer "F.Cu")
		(at 181.5084 -146.812)
		(property "Reference" "C4A10"
			(at 0 0 0)
			(layer "F.SilkS")
			(hide yes)
			(effects
				(font
					(size 1.27 1.27)
				)
			)
		)
		(property "Value" ""
			(at 0 0 0)
			(layer "F.Fab")
			(effects
				(font
					(size 1.27 1.27)
				)
			)
		)
		(duplicate_pad_numbers_are_jumpers no)
		(fp_rect
			(start 0.3048 -0.1016)
			(end -0.3048 0.9906)
			(stroke
				(width 0)
				(type default)
			)
			(fill no)
			(layer "F.CrtYd")
		)
		(fp_line
			(start -0.3048 -0.1016)
			(end -0.3048 0.9906)
			(stroke
				(width 0.1)
				(type default)
			)
			(layer "F.Fab")
		)
		(fp_line
			(start -0.3048 0.9906)
			(end 0.3048 0.9906)
			(stroke
				(width 0.1)
				(type default)
			)
			(layer "F.Fab")
		)
		(fp_line
			(start 0.3048 -0.1016)
			(end -0.3048 -0.1016)
			(stroke
				(width 0.1)
				(type default)
			)
			(layer "F.Fab")
		)
		(fp_line
			(start 0.3048 0.9906)
			(end 0.3048 -0.1016)
			(stroke
				(width 0.1)
				(type default)
			)
			(layer "F.Fab")
		)
		(pad "1" smd rect
			(at 0 0)
			(size 0.508 0.508)
			(layers "F.Cu" "F.Mask" "F.Paste")
			(net "VR_PVTT_DEF_BIAS")
		)
		(pad "2" smd rect
			(at 0 0.889)
			(size 0.508 0.508)
			(layers "F.Cu" "F.Mask" "F.Paste")
			(net "GND")
		)
		(zone
			(layer "F.Cu")
			(hatch none 0.5)
			(connect_pads
				(clearance 0)
			)
			(min_thickness 0.25)
			(keepout
				(tracks not_allowed)
				(vias allowed)
				(pads allowed)
				(copperpour not_allowed)
				(footprints allowed)
			)
			(placement
				(enabled no)
				(sheetname "")
			)
			(fill
				(thermal_gap 0.5)
				(thermal_bridge_width 0.5)
				(island_removal_mode 0)
			)
			(polygon
				(pts
					(xy 181.7624 -146.558) (xy 181.2544 -146.558) (xy 181.2544 -146.177) (xy 181.7624 -146.177)
				)
			)
		)
		(zone
			(layer "F.Cu")
			(hatch none 0.5)
			(connect_pads
				(clearance 0)
			)
			(min_thickness 0.25)
			(keepout
				(tracks allowed)
				(vias not_allowed)
				(pads allowed)
				(copperpour not_allowed)
				(footprints allowed)
			)
			(placement
				(enabled no)
				(sheetname "")
			)
			(fill
				(thermal_gap 0.5)
				(thermal_bridge_width 0.5)
				(island_removal_mode 0)
			)
			(polygon
				(pts
					(xy 181.7624 -146.558) (xy 181.2544 -146.558) (xy 181.2544 -146.177) (xy 181.7624 -146.177)
				)
			)
		)
	)
	(footprint ""
		(layer "F.Cu")
		(at 205.036928 -89.289382)
		(property "Reference" "L4C3"
			(at 3.378708 -4.251706 0)
			(unlocked yes)
			(layer "F.SilkS")
			(effects
				(font
					(size 0.4064 0.254)
					(thickness 0.1524)
				)
			)
		)
		(property "Value" ""
			(at 0 0 0)
			(layer "F.Fab")
			(effects
				(font
					(size 1.27 1.27)
				)
			)
		)
		(duplicate_pad_numbers_are_jumpers no)
		(fp_line
			(start -1.1303 -3.199892)
			(end 8.3693 -3.199892)
			(stroke
				(width 0.1524)
				(type default)
			)
			(layer "F.SilkS")
		)
		(fp_line
			(start -1.1303 -1.6637)
			(end -1.1303 -3.199892)
			(stroke
				(width 0.1524)
				(type default)
			)
			(layer "F.SilkS")
		)
		(fp_line
			(start -1.1303 3.199892)
			(end -1.1303 1.6637)
			(stroke
				(width 0.1524)
				(type default)
			)
			(layer "F.SilkS")
		)
		(fp_line
			(start 8.3693 -3.199892)
			(end 8.3693 -1.6637)
			(stroke
				(width 0.1524)
				(type default)
			)
			(layer "F.SilkS")
		)
		(fp_line
			(start 8.3693 1.6637)
			(end 8.3693 3.199892)
			(stroke
				(width 0.1524)
				(type default)
			)
			(layer "F.SilkS")
		)
		(fp_line
			(start 8.3693 3.199892)
			(end -1.1303 3.199892)
			(stroke
				(width 0.1524)
				(type default)
			)
			(layer "F.SilkS")
		)
		(fp_rect
			(start -1.1303 3.199892)
			(end 8.3693 -3.199892)
			(stroke
				(width 0)
				(type default)
			)
			(fill no)
			(layer "F.CrtYd")
		)
		(fp_line
			(start -1.1303 -3.199892)
			(end 8.3693 -3.199892)
			(stroke
				(width 0.1)
				(type default)
			)
			(layer "F.Fab")
		)
		(fp_line
			(start -1.1303 3.199892)
			(end -1.1303 -3.199892)
			(stroke
				(width 0.1)
				(type default)
			)
			(layer "F.Fab")
		)
		(fp_line
			(start 8.3693 -3.199892)
			(end 8.3693 3.199892)
			(stroke
				(width 0.1)
				(type default)
			)
			(layer "F.Fab")
		)
		(fp_line
			(start 8.3693 3.199892)
			(end -1.1303 3.199892)
			(stroke
				(width 0.1)
				(type default)
			)
			(layer "F.Fab")
		)
		(pad "1" smd rect
			(at 0 0)
			(size 3.683 2.667)
			(layers "F.Cu" "F.Mask" "F.Paste")
			(net "VR_PVCCIN_CPU0_PHASE5")
		)
		(pad "2" smd rect
			(at 7.239 0)
			(size 3.683 2.667)
			(layers "F.Cu" "F.Mask" "F.Paste")
			(net "PVCCIN_CPU0")
		)
	)
)
